(kicad_pcb
	(version 20241229)
	(generator "pcbnew")
	(generator_version "9.0")
	(general
		(thickness 1.711)
		(legacy_teardrops no)
	)
	(paper "A4")
	(title_block
		(title "Antmicro Baseboard for Jetson AGX Thor")
		(date "2026-02-18")
		(rev "1.1.0")
		(company "Antmicro Ltd")
		(comment 1 "www.antmicro.com")
		(comment 9 "footprints 893-895 of 1170")
	)
	(layers
		(0 "F.Cu" signal)
		(4 "In1.Cu" signal)
		(6 "In2.Cu" signal)
		(8 "In3.Cu" signal)
		(10 "In4.Cu" jumper)
		(12 "In5.Cu" signal)
		(14 "In6.Cu" signal)
		(16 "In7.Cu" signal)
		(18 "In8.Cu" signal)
		(2 "B.Cu" signal)
		(9 "F.Adhes" user "F.Adhesive")
		(11 "B.Adhes" user "B.Adhesive")
		(13 "F.Paste" user)
		(15 "B.Paste" user)
		(5 "F.SilkS" user "F.Silkscreen")
		(7 "B.SilkS" user "B.Silkscreen")
		(1 "F.Mask" user)
		(3 "B.Mask" user)
		(17 "Dwgs.User" user "User.Drawings")
		(19 "Cmts.User" user "User.Comments")
		(21 "Eco1.User" user "User.Eco1")
		(23 "Eco2.User" user "User.Eco2")
		(25 "Edge.Cuts" user)
		(27 "Margin" user)
		(31 "F.CrtYd" user "F.Courtyard")
		(29 "B.CrtYd" user "B.Courtyard")
		(35 "F.Fab" user)
		(33 "B.Fab" user)
	)
	(footprint "antmicro-footprints:R_0402_1005Metric"
		(layer "B.Cu")
		(at 137.8 65.2 90)
		(descr "Resistor SMD 0402")
		(tags "resistor SMD 0402")
		(property "Reference" "R236"
			(at -3.7 -0.4 90)
			(layer "B.SilkS")
			(effects
				(font
					(size 0.7 0.7)
					(thickness 0.15)
				)
				(justify right top mirror)
			)
		)
		(property "Value" "R_100k_0402"
			(at -1.011843 -1.772046 90)
			(layer "B.Fab")
			(effects
				(font
					(size 0.7 0.7)
					(thickness 0.15)
				)
				(justify right top mirror)
			)
		)
		(property "Datasheet" "https://www.bourns.com/docs/product-datasheets/cr.pdf"
			(at 0 0 90)
			(layer "B.Fab")
			(hide yes)
			(effects
				(font
					(size 1.27 1.27)
					(thickness 0.15)
				)
				(justify mirror)
			)
		)
		(property "Description" "SMD Chip Resistor, 100 kohm, ± 1%, 62.5 mW, 0402 [1005 Metric], Thick Film, General Purpose"
			(at 0 0 90)
			(layer "B.Fab")
			(hide yes)
			(effects
				(font
					(size 1.27 1.27)
					(thickness 0.15)
				)
				(justify mirror)
			)
		)
		(property "Manufacturer" "Bourns"
			(at 0 0 270)
			(unlocked yes)
			(layer "B.Fab")
			(hide yes)
			(effects
				(font
					(size 1 1)
					(thickness 0.15)
				)
				(justify mirror)
			)
		)
		(property "MPN" "CR0402-FX-1003GLF"
			(at 0 0 270)
			(unlocked yes)
			(layer "B.Fab")
			(hide yes)
			(effects
				(font
					(size 1 1)
					(thickness 0.15)
				)
				(justify mirror)
			)
		)
		(property "Val" "100k"
			(at 0 0 270)
			(unlocked yes)
			(layer "B.Fab")
			(hide yes)
			(effects
				(font
					(size 1 1)
					(thickness 0.15)
				)
				(justify mirror)
			)
		)
		(property "License" "Apache-2.0"
			(at 0 0 270)
			(unlocked yes)
			(layer "B.Fab")
			(hide yes)
			(effects
				(font
					(size 1 1)
					(thickness 0.15)
				)
				(justify mirror)
			)
		)
		(property "Author" "Antmicro"
			(at 0 0 270)
			(unlocked yes)
			(layer "B.Fab")
			(hide yes)
			(effects
				(font
					(size 1 1)
					(thickness 0.15)
				)
				(justify mirror)
			)
		)
		(property "Tolerance" "1%"
			(at 0 0 270)
			(unlocked yes)
			(layer "B.Fab")
			(hide yes)
			(effects
				(font
					(size 1 1)
					(thickness 0.15)
				)
				(justify mirror)
			)
		)
		(sheetname "/Peripherals/")
		(sheetfile "peripherals.kicad_sch")
		(attr smd exclude_from_pos_files exclude_from_bom dnp)
		(fp_poly
			(pts
				(xy -0.925 0.47) (xy -0.925 -0.47) (xy 0.925 -0.47) (xy 0.925 0.47)
			)
			(stroke
				(width 0.05)
				(type default)
			)
			(fill no)
			(layer "B.CrtYd")
		)
		(fp_poly
			(pts
				(xy -0.5 0.25) (xy -0.5 -0.25) (xy 0.5 -0.25) (xy 0.5 0.25)
			)
			(stroke
				(width 0.15)
				(type solid)
			)
			(fill no)
			(layer "B.Fab")
		)
		(fp_text user "Author: Antmicro"
			(at -0.95 -4.169 90)
			(layer "B.Fab")
			(effects
				(font
					(size 0.7 0.7)
					(thickness 0.15)
				)
				(justify right top mirror)
			)
		)
		(fp_text user "License: Apache-2.0"
			(at -0.949999 -5.169 90)
			(layer "B.Fab")
			(effects
				(font
					(size 0.7 0.7)
					(thickness 0.15)
				)
				(justify right top mirror)
			)
		)
		(fp_text user "${REFERENCE}"
			(at -0.95 -3.168 90)
			(layer "B.Fab")
			(effects
				(font
					(size 0.7 0.7)
					(thickness 0.15)
				)
				(justify right top mirror)
			)
		)
		(pad "1" smd roundrect
			(at -0.48 0 90)
			(size 0.59 0.64)
			(layers "B.Cu" "B.Mask" "B.Paste")
			(roundrect_rratio 0.25)
			(net 1 "GND")
			(pintype "passive")
		)
		(pad "2" smd roundrect
			(at 0.48 0 90)
			(size 0.59 0.64)
			(layers "B.Cu" "B.Mask" "B.Paste")
			(roundrect_rratio 0.25)
			(net 90 "/Peripherals/I2C_CONN_PEN")
			(pintype "passive")
		)
	)
	(footprint "antmicro-footprints:SOT-563"
		(layer "B.Cu")
		(at 219.89 121.651698 90)
		(property "Reference" "Q29"
			(at -0.648302 1.21 90)
			(layer "B.SilkS")
			(effects
				(font
					(size 0.7 0.7)
					(thickness 0.15)
				)
				(justify right top mirror)
			)
		)
		(property "Value" "DMC2400UV-7"
			(at 0 -2 90)
			(layer "B.Fab")
			(effects
				(font
					(size 0.7 0.7)
					(thickness 0.15)
				)
				(justify right top mirror)
			)
		)
		(property "Datasheet" "https://www.mouser.com/datasheet/2/115/DIOD_S_A0010038249_1-2543538.pdf"
			(at 0 0 90)
			(layer "B.Fab")
			(hide yes)
			(effects
				(font
					(size 1.27 1.27)
					(thickness 0.15)
				)
				(justify mirror)
			)
		)
		(property "Description" "Dual MOSFET, Complementary N and P Channel, 20 V, 20 V, 1.03 A, 1.03 A, 0.3 ohm"
			(at 0 0 90)
			(layer "B.Fab")
			(hide yes)
			(effects
				(font
					(size 1.27 1.27)
					(thickness 0.15)
				)
				(justify mirror)
			)
		)
		(property "MPN" "DMC2400UV-7"
			(at 0 0 270)
			(unlocked yes)
			(layer "B.Fab")
			(hide yes)
			(effects
				(font
					(size 1 1)
					(thickness 0.15)
				)
				(justify mirror)
			)
		)
		(property "Manufacturer" "Diodes Incorporated"
			(at 0 0 270)
			(unlocked yes)
			(layer "B.Fab")
			(hide yes)
			(effects
				(font
					(size 1 1)
					(thickness 0.15)
				)
				(justify mirror)
			)
		)
		(property "Author" "Antmicro"
			(at 0 0 270)
			(unlocked yes)
			(layer "B.Fab")
			(hide yes)
			(effects
				(font
					(size 1 1)
					(thickness 0.15)
				)
				(justify mirror)
			)
		)
		(property "License" "Apache-2.0"
			(at 0 0 270)
			(unlocked yes)
			(layer "B.Fab")
			(hide yes)
			(effects
				(font
					(size 1 1)
					(thickness 0.15)
				)
				(justify mirror)
			)
		)
		(sheetname "/USB Hub/")
		(sheetfile "usb_hub.kicad_sch")
		(attr smd)
		(fp_line
			(start 0.776 -0.972)
			(end 0.526 -0.972)
			(stroke
				(width 0.15)
				(type solid)
			)
			(layer "B.SilkS")
		)
		(fp_line
			(start -0.778 -0.949)
			(end -0.424 -0.949)
			(stroke
				(width 0.15)
				(type solid)
			)
			(layer "B.SilkS")
		)
		(fp_line
			(start 0.776 -0.776)
			(end 0.776 -0.972)
			(stroke
				(width 0.15)
				(type solid)
			)
			(layer "B.SilkS")
		)
		(fp_line
			(start -0.778 -0.776)
			(end -0.778 -0.949)
			(stroke
				(width 0.15)
				(type solid)
			)
			(layer "B.SilkS")
		)
		(fp_line
			(start 0.776 0.974)
			(end 0.776 0.778)
			(stroke
				(width 0.15)
				(type solid)
			)
			(layer "B.SilkS")
		)
		(fp_line
			(start 0.776 0.974)
			(end 0.526 0.974)
			(stroke
				(width 0.15)
				(type solid)
			)
			(layer "B.SilkS")
		)
		(fp_line
			(start -0.499 0.974)
			(end -0.724 0.778)
			(stroke
				(width 0.15)
				(type solid)
			)
			(layer "B.SilkS")
		)
		(fp_circle
			(center -0.903 0.999)
			(end -0.952 0.95)
			(stroke
				(width 0.15)
				(type solid)
			)
			(fill yes)
			(layer "B.SilkS")
		)
		(fp_rect
			(start 1.19 1.12)
			(end -1.2 -1.1)
			(stroke
				(width 0.05)
				(type solid)
			)
			(fill no)
			(layer "B.CrtYd")
		)
		(fp_line
			(start 0.651 -0.847)
			(end -0.653 -0.847)
			(stroke
				(width 0.15)
				(type solid)
			)
			(layer "B.Fab")
		)
		(fp_line
			(start -0.653 0.678)
			(end -0.653 -0.847)
			(stroke
				(width 0.15)
				(type solid)
			)
			(layer "B.Fab")
		)
		(fp_line
			(start 0.651 0.849)
			(end 0.651 -0.847)
			(stroke
				(width 0.15)
				(type solid)
			)
			(layer "B.Fab")
		)
		(fp_line
			(start -0.453 0.849)
			(end -0.653 0.678)
			(stroke
				(width 0.15)
				(type solid)
			)
			(layer "B.Fab")
		)
		(fp_line
			(start -0.453 0.849)
			(end 0.651 0.849)
			(stroke
				(width 0.15)
				(type solid)
			)
			(layer "B.Fab")
		)
		(fp_text user "License: Apache-2.0"
			(at -1.299 -4.924 90)
			(layer "B.Fab")
			(effects
				(font
					(size 0.7 0.7)
					(thickness 0.15)
				)
				(justify right top mirror)
			)
		)
		(fp_text user "Author: Antmicro"
			(at -1.299 -6.124 90)
			(layer "B.Fab")
			(effects
				(font
					(size 0.7 0.7)
					(thickness 0.15)
				)
				(justify right top mirror)
			)
		)
		(fp_text user "${REFERENCE}"
			(at -1.299 -7.323 90)
			(layer "B.Fab")
			(effects
				(font
					(size 0.7 0.7)
					(thickness 0.15)
				)
				(justify right top mirror)
			)
		)
		(pad "1" smd roundrect
			(at -0.749 0.499 180)
			(size 0.3 0.6)
			(layers "B.Cu" "B.Mask" "B.Paste")
			(roundrect_rratio 0.25)
			(net 1 "GND")
			(pinfunction "S1")
			(pintype "passive")
		)
		(pad "2" smd roundrect
			(at -0.749 -0.001 180)
			(size 0.3 0.6)
			(layers "B.Cu" "B.Mask" "B.Paste")
			(roundrect_rratio 0.25)
			(net 1095 "/USB Hub/DP1_VCONN2")
			(pinfunction "G1")
			(pintype "input")
		)
		(pad "3" smd roundrect
			(at -0.749 -0.497 180)
			(size 0.3 0.6)
			(layers "B.Cu" "B.Mask" "B.Paste")
			(roundrect_rratio 0.25)
			(net 1240 "Net-(D60-A)")
			(pinfunction "D2")
			(pintype "passive")
		)
		(pad "4" smd roundrect
			(at 0.747 -0.497 180)
			(size 0.3 0.6)
			(layers "B.Cu" "B.Mask" "B.Paste")
			(roundrect_rratio 0.25)
			(net 5 "+5V")
			(pinfunction "S2")
			(pintype "passive")
		)
		(pad "5" smd roundrect
			(at 0.747 -0.001 180)
			(size 0.3 0.6)
			(layers "B.Cu" "B.Mask" "B.Paste")
			(roundrect_rratio 0.25)
			(net 1333 "Net-(Q29-D1)")
			(pinfunction "G2")
			(pintype "input")
		)
		(pad "6" smd roundrect
			(at 0.747 0.499 180)
			(size 0.3 0.6)
			(layers "B.Cu" "B.Mask" "B.Paste")
			(roundrect_rratio 0.25)
			(net 1333 "Net-(Q29-D1)")
			(pinfunction "D1")
			(pintype "passive")
		)
	)
	(footprint "antmicro-footprints:Conn_Plug_Samtec_UMPT_1x6_UMPT-06-02.5-L-V-S-W-TR"
		(layer "B.Cu")
		(at 93.930532 134.21 -90)
		(property "Reference" "J8"
			(at -10.32 4.75 90)
			(layer "B.SilkS")
			(effects
				(font
					(size 0.7 0.7)
					(thickness 0.15)
				)
				(justify left bottom mirror)
			)
		)
		(property "Value" "Plug_Samtec_UMPT_1x6_UMPT-06-02.5-L-V-S-W-TR"
			(at -10.32 -5.3 90)
			(layer "B.Fab")
			(effects
				(font
					(size 0.7 0.7)
					(thickness 0.15)
				)
				(justify left bottom mirror)
			)
		)
		(property "Datasheet" "https://suddendocs.samtec.com/catalog_english/umpt.pdf"
			(at 0 0 90)
			(layer "B.Fab")
			(effects
				(font
					(size 0.7 0.7)
					(thickness 0.15)
				)
				(justify right top mirror)
			)
		)
		(property "Description" "2.00 mm mPOWER® Ultra Micro Power Terminal, Vertical"
			(at 0 0 90)
			(layer "B.Fab")
			(effects
				(font
					(size 0.7 0.7)
					(thickness 0.15)
				)
				(justify right top mirror)
			)
		)
		(property "MPN" "UMPT-06-02.5-L-V-S-W-TR"
			(at 0 0 270)
			(unlocked yes)
			(layer "B.Fab")
			(hide yes)
			(effects
				(font
					(size 1 1)
					(thickness 0.15)
				)
				(justify mirror)
			)
		)
		(property "Manufacturer" "Samtec"
			(at 0 0 270)
			(unlocked yes)
			(layer "B.Fab")
			(hide yes)
			(effects
				(font
					(size 1 1)
					(thickness 0.15)
				)
				(justify mirror)
			)
		)
		(property "Author" "Antmicro"
			(at 0 0 270)
			(unlocked yes)
			(layer "B.Fab")
			(hide yes)
			(effects
				(font
					(size 1 1)
					(thickness 0.15)
				)
				(justify mirror)
			)
		)
		(property "License" "Apache-2.0"
			(at 0 0 270)
			(unlocked yes)
			(layer "B.Fab")
			(hide yes)
			(effects
				(font
					(size 1 1)
					(thickness 0.15)
				)
				(justify mirror)
			)
		)
		(sheetname "/Expansion connector/")
		(sheetfile "expansion_connector.kicad_sch")
		(attr smd)
		(fp_line
			(start -9.05 3.8)
			(end -9.65 3.2)
			(stroke
				(width 0.15)
				(type solid)
			)
			(layer "B.SilkS")
		)
		(fp_line
			(start 9.65 3.8)
			(end -9.05 3.8)
			(stroke
				(width 0.15)
				(type solid)
			)
			(layer "B.SilkS")
		)
		(fp_line
			(start 9.65 3.8)
			(end 9.65 3.53)
			(stroke
				(width 0.15)
				(type solid)
			)
			(layer "B.SilkS")
		)
		(fp_line
			(start -9.65 3.2)
			(end -9.65 3.03)
			(stroke
				(width 0.15)
				(type solid)
			)
			(layer "B.SilkS")
		)
		(fp_line
			(start 9.65 -2.13)
			(end 9.65 -3.8)
			(stroke
				(width 0.15)
				(type solid)
			)
			(layer "B.SilkS")
		)
		(fp_line
			(start -9.65 -2.63)
			(end -9.65 -3.8)
			(stroke
				(width 0.15)
				(type solid)
			)
			(layer "B.SilkS")
		)
		(fp_line
			(start 9.65 -3.8)
			(end -9.65 -3.8)
			(stroke
				(width 0.15)
				(type solid)
			)
			(layer "B.SilkS")
		)
		(fp_circle
			(center -5 4.04)
			(end -4.95 4.04)
			(stroke
				(width 0.15)
				(type solid)
			)
			(fill yes)
			(layer "B.SilkS")
		)
		(fp_rect
			(start -10.05 4.2)
			(end 10.05 -4.2)
			(stroke
				(width 0.05)
				(type solid)
			)
			(fill no)
			(layer "B.CrtYd")
		)
		(fp_line
			(start -9.05 3.8)
			(end -9.65 3.2)
			(stroke
				(width 0.15)
				(type solid)
			)
			(layer "B.Fab")
		)
		(fp_line
			(start 9.65 3.8)
			(end -9.05 3.8)
			(stroke
				(width 0.15)
				(type solid)
			)
			(layer "B.Fab")
		)
		(fp_line
			(start -9.65 3.2)
			(end -9.65 -3.8)
			(stroke
				(width 0.15)
				(type solid)
			)
			(layer "B.Fab")
		)
		(fp_line
			(start -9.65 -3.8)
			(end 9.65 -3.8)
			(stroke
				(width 0.15)
				(type solid)
			)
			(layer "B.Fab")
		)
		(fp_line
			(start 9.65 -3.8)
			(end 9.65 3.8)
			(stroke
				(width 0.15)
				(type solid)
			)
			(layer "B.Fab")
		)
		(fp_text user "${REFERENCE}"
			(at -10.32 -8.9 90)
			(layer "B.Fab")
			(effects
				(font
					(size 0.7 0.7)
					(thickness 0.15)
				)
				(justify left bottom mirror)
			)
		)
		(fp_text user "Author: Antmicro"
			(at -10.32 -7.7 90)
			(layer "B.Fab")
			(effects
				(font
					(size 0.7 0.7)
					(thickness 0.15)
				)
				(justify left bottom mirror)
			)
		)
		(fp_text user "License: Apache-2.0"
			(at -10.32 -6.5 90)
			(layer "B.Fab")
			(effects
				(font
					(size 0.7 0.7)
					(thickness 0.15)
				)
				(justify left bottom mirror)
			)
		)
		(pad "1" smd rect
			(at -5 0 90)
			(size 1.25 3.5)
			(layers "B.Cu" "B.Mask" "B.Paste")
			(net 297 "/Expansion connector/+3V3_FMC")
			(pintype "passive")
			(solder_mask_margin 0.102)
		)
		(pad "2" smd rect
			(at -3 0 90)
			(size 1.25 3.5)
			(layers "B.Cu" "B.Mask" "B.Paste")
			(net 307 "/Expansion connector/+5V_FMC")
			(pintype "passive")
			(solder_mask_margin 0.102)
		)
		(pad "3" smd rect
			(at -1 0 90)
			(size 1.25 3.5)
			(layers "B.Cu" "B.Mask" "B.Paste")
			(net 156 "/Expansion connector/+VCC_FMC")
			(pintype "passive")
			(solder_mask_margin 0.102)
		)
		(pad "4" smd rect
			(at 1 0 90)
			(size 1.25 3.5)
			(layers "B.Cu" "B.Mask" "B.Paste")
			(net 156 "/Expansion connector/+VCC_FMC")
			(pintype "passive")
			(solder_mask_margin 0.102)
		)
		(pad "5" smd rect
			(at 3 0 90)
			(size 1.25 3.5)
			(layers "B.Cu" "B.Mask" "B.Paste")
			(net 1 "GND")
			(pintype "passive")
			(solder_mask_margin 0.102)
		)
		(pad "6" smd rect
			(at 5 0 90)
			(size 1.25 3.5)
			(layers "B.Cu" "B.Mask" "B.Paste")
			(net 1 "GND")
			(pintype "passive")
			(solder_mask_margin 0.102)
		)
		(pad "MP1" thru_hole circle
			(at 8.85 -0.3 90)
			(size 1.308 1.308)
			(drill 0.8)
			(layers "*.Cu" "*.Mask")
			(remove_unused_layers no)
			(net 1 "GND")
			(pintype "passive")
			(solder_mask_margin 0.102)
		)
		(pad "MP1" thru_hole circle
			(at 8.85 1.7 90)
			(size 1.308 1.308)
			(drill 0.8)
			(layers "*.Cu" "*.Mask")
			(remove_unused_layers no)
			(net 1 "GND")
			(pintype "passive")
			(solder_mask_margin 0.102)
		)
		(pad "MP2" thru_hole circle
			(at -8.85 -0.8 90)
			(size 1.308 1.308)
			(drill 0.8)
			(layers "*.Cu" "*.Mask")
			(remove_unused_layers no)
			(net 1 "GND")
			(pintype "passive")
			(solder_mask_margin 0.102)
		)
		(pad "MP2" thru_hole circle
			(at -8.85 1.2 90)
			(size 1.308 1.308)
			(drill 0.8)
			(layers "*.Cu" "*.Mask")
			(remove_unused_layers no)
			(net 1 "GND")
			(pintype "passive")
			(solder_mask_margin 0.102)
		)
	)
)
